FILE_TYPE = CONNECTIVITY;
{Allegro Design Entry HDL 17.2-2016 S067 (3860444) 4/26/2020}
"PAGE_NUMBER" = 127;
0"NC";
1"SG\g";
2"SG\g";
3"SG\g";
4"SG\g";
5"XP3R3V_FPGA\g";
6"XP3R3V_FPGA\g";
7"XP3R3V_FPGA\g";
8"SG\g";
9"SG\g";
10"SG\g";
11"XP3R3V_FPGA\g";
12"XP3R3V_FPGA\g";
13"SG\g";
14"XP3R3V_FPGA\g";
15"XP3R3V_FPGA\g";
16"XP3R3V_FPGA\g";
17"FPGA_MGTAVTT\g";
18"SG\g";
19"SG\g";
20"FPGA_TDI";
21"FT4232_FPGA_TCK";
22"FT4232_FPGA_TDI";
23"FT4232_FPGA_TDO";
24"FT4232_FPGA_TMS";
25"FLASH_DQ2";
26"FLASH_DQ1_MISO";
27"UN$127$MT25QL128ABA1ESESOP8$I456$DQ0";
28"UN$127$MT25QL128ABA1ESESOP8$I456$W";
29"FLASH_DQ0_MOSI";
30"FPGA_M2";
31"FLASH_DQ3";
32"FLASH_CLK";
33"FLASH_CS_N";
34"UN$127$MT25QL128ABA1ESESOP8$I456$HOLD";
35"UN$127$MT25QL128ABA1ESESOP8$I456$DQ1";
36"CCLK_0";
37"FPGA_M0";
38"FPGA_M0";
39"FPGA_M1";
40"FPGA_BRD_REV1";
41"FPGA_BRD_REV2";
42"R_FPGA_TDO";
43"FPGA_TMS";
44"UN$127$G2001028301$I427$4";
45"CPU_RX_PCIE_MGT0_TXP";
46"CPU_RX_PCIE_MGT0_TXN";
47"CPU_RX_PCIE_MGT1_TXP";
48"CPU_RX_PCIE_MGT1_TXN";
49"CPU_RX_PCIE_MGT2_TXN";
50"CPU_RX_PCIE_MGT2_TXP";
51"CPU_RX_PCIE_MGT3_TXP";
52"CPU_RX_PCIE_MGT3_TXN";
53"CPU_TX_PCIE_MGT_3_RXN";
54"CPU_TX_PCIE_MGT_3_RXP";
55"CPU_TX_PCIE_MGT_2_RXN";
56"CPU_TX_PCIE_MGT_2_RXP";
57"CPU_TX_PCIE_MGT_1_RXN";
58"CPU_TX_PCIE_MGT_1_RXP";
59"CPU_TX_PCIE_MGT_0_RXN";
60"CPU_TX_PCIE_MGT_0_RXP";
61"FPGA_TDO";
62"PCIE_REFCLKN";
63"MHZ125CLKP_CLKIN";
64"MHZ125CLKN_CLKIN";
65"FPGA_MGTRREF";
66"FPGA_M1";
67"FPGA_TCK";
68"FPGA_CFG_INIT_N";
69"FPGA_FLASH_CLK";
70"FPGA_M2";
71"FPGA_DONE";
72"FPGA_TDO";
73"FPGA_PROGRAM_N";
74"FPGA_TCK";
75"FPGA_TMS";
76"CFGBVS";
77"PCIE_REFCLKP";
78"FPGA_TDI";
79"FPGA_BRD_REV0";
%"GND_SG"
"1","(-9050,5500)","0","cls","I106";
;
HDL_POWER"SG"
BODY_TYPE"PLUMBING"
CDS_LIB"cls"
CDS_LMAN_SYM_OUTLINE"0,0,100,-50";
"SGND"19;
%"GND_SG"
"1","(-6350,5750)","0","cls","I130";
;
HDL_POWER"SG"
BODY_TYPE"PLUMBING"
CDS_LMAN_SYM_OUTLINE"0,0,100,-50"
CDS_LIB"cls";
"SGND"18;
%"XC7A200T_2FBG484C_FBG484"
"1","(-8550,7950)","0","pld","I232";
;
VALUE"XC7A100T-1FGG484I"
$LOCATION"U24"
CLS_PN"G240-10069-01"
CDS_SEC"1"
$SEC"1"
CDS_LOCATION"U24"
CDS_LIB"pld"
CDS_LMAN_SYM_OUTLINE"0,0,1800,-3400";
"VREFP_0"
$PN"M10"18;
"VREFN_0"
$PN"L9"18;
"VP_0"
$PN"L10"19;
"VN_0"
$PN"M9"19;
"TMS_0"
$PN"T13"75;
"TDO_0"
$PN"U13"42;
"TDI_0"
$PN"R13"78;
"TCK_0"
$PN"V12"74;
"PROGRAM_0* \B"
$PN"N12"73;
"MGTRREF_216"
$PN"F8"65;
"MGTREFCLK1P_216"
$PN"F10"77;
"MGTREFCLK1N_216"
$PN"E10"62;
"MGTREFCLK0P_216"
$PN"F6"63;
"MGTREFCLK0N_216"
$PN"E6"64;
"MGTPTXP3_216"
$PN"D7"51;
"MGTPTXP2_216"
$PN"B6"50;
"MGTPTXP1_216"
$PN"D5"47;
"MGTPTXP0_216"
$PN"B4"45;
"MGTPTXN3_216"
$PN"C7"52;
"MGTPTXN2_216"
$PN"A6"49;
"MGTPTXN1_216"
$PN"C5"48;
"MGTPTXN0_216"
$PN"A4"46;
"MGTPRXP3_216"
$PN"D9"54;
"MGTPRXP2_216"
$PN"B10"56;
"MGTPRXP1_216"
$PN"D11"58;
"MGTPRXP0_216"
$PN"B8"60;
"MGTPRXN3_216"
$PN"C9"53;
"MGTPRXN2_216"
$PN"A10"55;
"MGTPRXN1_216"
$PN"C11"57;
"MGTPRXN0_216"
$PN"A8"59;
"M2_0"
$PN"U9"70;
"M1_0"
$PN"U10"66;
"M0_0"
$PN"U11"37;
"INIT_0* \B"
$PN"U12"68;
"DXP_0"
$PN"N10"19;
"DXN_0"
$PN"N9"19;
"DONE_0"
$PN"G11"71;
"CFGBVS_0"
$PN"U8"76;
"CCLK_0"
$PN"L12"36;
%"VCC"
"1","(-10700,5950)","0","cls","I243";
;
HDL_POWER"FPGA_MGTAVTT"
VOLTAGE"1.2"
BODY_TYPE"PLUMBING"
CDS_LMAN_SYM_OUTLINE"-250,250,250,-250"
CDS_LIB"cls";
"$PIN0"17;
%"RESISTOR"
"1","(-10350,4650)","0","passive","I329";
;
$LOCATION"R194"
PACKAGE"0402"
VALUE"4.7KOHM"
CDS_SEC"1"
$SEC"1"
CDS_LOCATION"R194"
TOLERANCE"1%"
CDS_LIB"passive"
CDS_LMAN_SYM_OUTLINE"-50,50,100,-50"
CLS_PN"G155-14701-01";
"1"
$PN"1"16;
"2"
$PN"2"76;
%"RESISTOR"
"1","(-10350,4750)","0","passive","I330";
;
$LOCATION"R193"
VALUE"4.7KOHM"
PACKAGE"0402"
CDS_SEC"1"
$SEC"1"
CDS_LOCATION"R193"
TOLERANCE"1%"
CLS_PN"G155-14701-01"
CDS_LIB"passive"
CDS_LMAN_SYM_OUTLINE"-50,50,100,-50";
"1"
$PN"1"16;
"2"
$PN"2"73;
%"RESISTOR"
"1","(-9950,5150)","0","passive","I331";
;
$LOCATION"R195"
PACKAGE"0402"
VALUE"33OHM"
CDS_SEC"1"
$SEC"1"
CDS_LOCATION"R195"
TOLERANCE"1%"
CLS_PN"G155-133R0-01"
CDS_LIB"passive"
CDS_LMAN_SYM_OUTLINE"-50,50,100,-50";
"1"
$PN"1"61;
"2"
$PN"2"42;
%"RESISTOR"
"1","(-10150,5800)","0","passive","I332";
;
$LOCATION"R196"
VALUE"100OHM"
PACKAGE"0402"
CDS_SEC"1"
$SEC"1"
CDS_LOCATION"R196"
TOLERANCE"1%"
CLS_PN"G155-11000-01"
CDS_LIB"passive"
CDS_LMAN_SYM_OUTLINE"-50,50,100,-50";
"1"
$PN"1"17;
"2"
$PN"2"65;
%"RESISTOR"
"1","(-9500,6450)","0","passive","I333";
;
$LOCATION"R197"
NO_ASSY"TRUE"
VALUE"100OHM"
PACKAGE"0402"
CDS_SEC"1"
$SEC"1"
CDS_LOCATION"R197"
TOLERANCE"1%"
CLS_PN"G155-11000-01"
CDS_LMAN_SYM_OUTLINE"-50,50,100,-50"
CDS_LIB"passive";
"1"
$PN"1"63;
"2"
$PN"2"64;
%"RESISTOR"
"1","(-9500,6150)","0","passive","I334";
;
$LOCATION"R198"
NO_ASSY"TRUE"
VALUE"100OHM"
PACKAGE"0402"
CDS_SEC"1"
$SEC"1"
CDS_LOCATION"R198"
TOLERANCE"1%"
CDS_LIB"passive"
CDS_LMAN_SYM_OUTLINE"-50,50,100,-50"
CLS_PN"G155-11000-01";
"1"
$PN"1"77;
"2"
$PN"2"62;
%"RESISTOR"
"1","(-5750,5150)","0","passive","I337";
;
$LOCATION"R207"
VALUE"0OHM"
CDS_SEC"1"
$SEC"1"
CDS_LOCATION"R207"
CLS_PN"G155-100R0-J0"
TOLERANCE"-"
CDS_LIB"passive"
CDS_LMAN_SYM_OUTLINE"-50,50,100,-50";
"1"
$PN"1"36;
"2"
$PN"2"69;
%"RESISTOR"
"1","(-3600,4650)","0","passive","I338";
;
$LOCATION"R210"
VALUE"330OHM"
CDS_SEC"1"
$SEC"1"
CDS_LOCATION"R210"
TOLERANCE"1%"
CLS_PN"G155-13300-01"
CDS_LIB"passive"
CDS_LMAN_SYM_OUTLINE"-50,50,100,-50";
"1"
$PN"1"71;
"2"
$PN"2"14;
%"RESISTOR"
"1","(-3600,4750)","0","passive","I339";
;
$LOCATION"R209"
VALUE"4.7KOHM"
CDS_SEC"1"
$SEC"1"
CDS_LOCATION"R209"
TOLERANCE"1%"
CLS_PN"G155-14701-01"
CDS_LMAN_SYM_OUTLINE"-50,50,100,-50"
CDS_LIB"passive";
"1"
$PN"1"68;
"2"
$PN"2"14;
%"VCC"
"1","(-11800,5600)","0","cls","I385";
;
VOLTAGE"3.3V"
HDL_POWER"XP3R3V_FPGA"
BODY_TYPE"PLUMBING"
CDS_LMAN_SYM_OUTLINE"-250,250,250,-250"
CDS_LIB"cls";
"$PIN0"16;
%"VCC"
"1","(-1050,3650)","0","cls","I389";
;
VOLTAGE"3.3V"
HDL_POWER"XP3R3V_FPGA"
CDS_LMAN_SYM_OUTLINE"-250,250,250,-250"
CDS_LIB"cls"
BODY_TYPE"PLUMBING";
"$PIN0"15;
%"VCC"
"1","(-2700,4900)","0","cls","I390";
;
HDL_POWER"XP3R3V_FPGA"
VOLTAGE"3.3V"
BODY_TYPE"PLUMBING"
CDS_LMAN_SYM_OUTLINE"-250,250,250,-250"
CDS_LIB"cls";
"$PIN0"14;
%"RESISTOR"
"2","(-5000,2600)","0","passive","I391";
;
$LOCATION"R216"
PACKAGE"0402"
VALUE"1KOHM"
CDS_SEC"1"
$SEC"1"
CDS_LOCATION"R216"
CLS_PN"G155-11001-01"
CDS_LMAN_SYM_OUTLINE"-50,50,50,-100"
CDS_LIB"passive"
TOLERANCE"1%";
"1"
$PN"1"40;
"2"
$PN"2"13;
%"RESISTOR"
"2","(-4550,3250)","0","passive","I392";
;
$LOCATION"R219"
VALUE"10KOHM"
PACKAGE"0402"
CDS_SEC"1"
$SEC"1"
CDS_LOCATION"R219"
CLS_PN"G155-11002-01"
CDS_LMAN_SYM_OUTLINE"-50,50,50,-100"
CDS_LIB"passive"
TOLERANCE"1%";
"1"
$PN"1"12;
"2"
$PN"2"79;
%"RESISTOR"
"2","(-4550,2600)","0","passive","I393";
;
$LOCATION"R220"
PACKAGE"0402"
VALUE"1KOHM"
NO_ASSY"TRUE"
CDS_SEC"1"
$SEC"1"
CDS_LOCATION"R220"
CLS_PN"G155-11001-01"
CDS_LMAN_SYM_OUTLINE"-50,50,50,-100"
CDS_LIB"passive"
TOLERANCE"1%";
"1"
$PN"1"79;
"2"
$PN"2"13;
%"RESISTOR"
"2","(-5000,3250)","0","passive","I394";
;
$LOCATION"R215"
NO_ASSY"TRUE"
VALUE"10KOHM"
PACKAGE"0402"
CDS_SEC"1"
$SEC"1"
CDS_LOCATION"R215"
CLS_PN"G155-11002-01"
CDS_LMAN_SYM_OUTLINE"-50,50,50,-100"
CDS_LIB"passive"
TOLERANCE"1%";
"1"
$PN"1"12;
"2"
$PN"2"40;
%"RESISTOR"
"2","(-5500,3250)","0","passive","I396";
;
$LOCATION"R213"
PACKAGE"0402"
VALUE"10KOHM"
NO_ASSY"TRUE"
CDS_SEC"1"
$SEC"1"
CDS_LOCATION"R213"
CLS_PN"G155-11002-01"
CDS_LMAN_SYM_OUTLINE"-50,50,50,-100"
CDS_LIB"passive"
TOLERANCE"1%";
"1"
$PN"1"12;
"2"
$PN"2"41;
%"RESISTOR"
"2","(-5500,2600)","0","passive","I397";
;
$LOCATION"R214"
PACKAGE"0402"
VALUE"1KOHM"
CDS_SEC"1"
$SEC"1"
CDS_LOCATION"R214"
CLS_PN"G155-11001-01"
CDS_LMAN_SYM_OUTLINE"-50,50,50,-100"
CDS_LIB"passive"
TOLERANCE"1%";
"1"
$PN"1"41;
"2"
$PN"2"13;
%"GND_SG"
"1","(-4600,2250)","0","cls","I398";
;
HDL_POWER"SG"
BODY_TYPE"PLUMBING"
CDS_LMAN_SYM_OUTLINE"0,0,100,-50"
CDS_LIB"cls";
"SGND"13;
%"RESISTOR"
"1","(-1500,3250)","5","passive","I402";
;
$LOCATION"R217"
VALUE"100OHM"
PACKAGE"0402"
NO_ASSY"TRUE"
CDS_SEC"1"
$SEC"1"
CDS_LOCATION"R217"
CLS_PN"G155-11000-01"
CDS_LMAN_SYM_OUTLINE"-50,50,100,-50"
CDS_LIB"passive"
TOLERANCE"1%";
"1"
$PN"1"15;
"2"
$PN"2"39;
%"RESISTOR"
"1","(-1000,3250)","5","passive","I403";
;
$LOCATION"R221"
VALUE"100OHM"
PACKAGE"0402"
NO_ASSY"TRUE"
CDS_SEC"1"
$SEC"1"
CDS_LOCATION"R221"
CLS_PN"G155-11000-01"
CDS_LMAN_SYM_OUTLINE"-50,50,100,-50"
CDS_LIB"passive"
TOLERANCE"1%";
"1"
$PN"1"15;
"2"
$PN"2"30;
%"RESISTOR"
"1","(-2000,3250)","5","passive","I404";
;
$LOCATION"R211"
PACKAGE"0402"
VALUE"100OHM"
CDS_SEC"1"
$SEC"1"
CDS_LOCATION"R211"
CDS_LIB"passive"
CDS_LMAN_SYM_OUTLINE"-50,50,100,-50"
CLS_PN"G155-11000-01"
TOLERANCE"1%";
"1"
$PN"1"15;
"2"
$PN"2"38;
%"RESISTOR"
"1","(-1000,2600)","5","passive","I405";
;
$LOCATION"R222"
VALUE"100OHM"
PACKAGE"0402"
CDS_SEC"1"
$SEC"1"
CDS_LOCATION"R222"
CDS_LIB"passive"
CDS_LMAN_SYM_OUTLINE"-50,50,100,-50"
CLS_PN"G155-11000-01"
TOLERANCE"1%";
"1"
$PN"1"30;
"2"
$PN"2"1;
%"RESISTOR"
"1","(-1500,2600)","5","passive","I406";
;
$LOCATION"R218"
VALUE"100OHM"
PACKAGE"0402"
CDS_SEC"1"
$SEC"1"
CDS_LOCATION"R218"
CDS_LIB"passive"
CDS_LMAN_SYM_OUTLINE"-50,50,100,-50"
CLS_PN"G155-11000-01"
TOLERANCE"1%";
"1"
$PN"1"39;
"2"
$PN"2"1;
%"RESISTOR"
"1","(-2000,2600)","5","passive","I407";
;
$LOCATION"R212"
NO_ASSY"TRUE"
PACKAGE"0402"
VALUE"100OHM"
CDS_SEC"1"
$SEC"1"
CDS_LOCATION"R212"
CDS_LIB"passive"
CDS_LMAN_SYM_OUTLINE"-50,50,100,-50"
CLS_PN"G155-11000-01"
TOLERANCE"1%";
"1"
$PN"1"38;
"2"
$PN"2"1;
%"VCC"
"1","(-4600,3600)","0","cls","I409";
;
HDL_POWER"XP3R3V_FPGA"
VOLTAGE"3.3V"
CDS_LIB"cls"
CDS_LMAN_SYM_OUTLINE"-250,250,250,-250"
BODY_TYPE"PLUMBING";
"$PIN0"12;
%"G200_10283_01"
"1","(-13250,650)","2","connector","I427";
;
$LOCATION"J14"
CLS_PN"G200-10283-01"
PART_NUMBER"95278-101A10LF"
CDS_SEC"1"
$SEC"1"
CDS_LOCATION"J14"
CDS_LIB"connector"
CDS_LMAN_SYM_OUTLINE"0,0,500,-1000";
"10"
$PN"10"8;
"9"
$PN"9"22;
"8"
$PN"8"0;
"7"
$PN"7"0;
"6"
$PN"6"0;
"5"
$PN"5"24;
"4"
$PN"4"44;
"3"
$PN"3"23;
"2"
$PN"2"8;
"1"
$PN"1"21;
%"RESISTOR"
"2","(-10450,1950)","0","passive","I432";
;
$LOCATION"R405"
VALUE"10KOHM"
PACKAGE"0402"
CDS_SEC"1"
$SEC"1"
CDS_LOCATION"R405"
CDS_LIB"passive"
CDS_LMAN_SYM_OUTLINE"-50,50,50,-100"
CLS_PN"G155-11002-01"
TOLERANCE"1%";
"1"
$PN"1"11;
"2"
$PN"2"20;
%"VCC"
"1","(-10500,2400)","0","cls","I433";
;
HDL_POWER"XP3R3V_FPGA"
VOLTAGE"3.3V"
CDS_LMAN_SYM_OUTLINE"-250,250,250,-250"
CDS_LIB"cls"
BODY_TYPE"PLUMBING";
"$PIN0"11;
%"RESISTOR"
"2","(-10800,1950)","0","passive","I434";
;
$LOCATION"R404"
VALUE"10KOHM"
PACKAGE"0402"
CDS_SEC"1"
$SEC"1"
CDS_LOCATION"R404"
CLS_PN"G155-11002-01"
CDS_LMAN_SYM_OUTLINE"-50,50,50,-100"
CDS_LIB"passive"
TOLERANCE"1%";
"1"
$PN"1"11;
"2"
$PN"2"43;
%"RESISTOR"
"2","(-11150,1950)","0","passive","I435";
;
$LOCATION"R403"
PACKAGE"0402"
VALUE"10KOHM"
CDS_SEC"1"
$SEC"1"
CDS_LOCATION"R403"
CLS_PN"G155-11002-01"
CDS_LMAN_SYM_OUTLINE"-50,50,50,-100"
CDS_LIB"passive"
TOLERANCE"1%";
"1"
$PN"1"11;
"2"
$PN"2"72;
%"RESISTOR"
"1","(-11800,1600)","0","passive","I436";
;
$LOCATION"R134"
PACKAGE"0402"
VALUE"33OHM"
CDS_SEC"1"
$SEC"1"
CDS_LOCATION"R134"
SIGNAL_MODEL"DEFAULT_RESISTOR_33OHM_2_1"
CDS_LMAN_SYM_OUTLINE"-50,50,100,-50"
CDS_LIB"passive"
CLS_PN"G155-133R0-01"
TOLERANCE"1%";
"1"
$PN"1"21;
"2"
$PN"2"67;
%"RESISTOR"
"1","(-11800,1200)","0","passive","I437";
;
$LOCATION"R136"
PACKAGE"0402"
VALUE"33OHM"
CDS_SEC"1"
$SEC"1"
CDS_LOCATION"R136"
CLS_PN"G155-133R0-01"
TOLERANCE"1%"
CDS_LMAN_SYM_OUTLINE"-50,50,100,-50"
CDS_LIB"passive";
"1"
$PN"1"24;
"2"
$PN"2"43;
%"RESISTOR"
"1","(-11800,1400)","0","passive","I438";
;
$LOCATION"R135"
PACKAGE"0402"
VALUE"0OHM"
CDS_SEC"1"
$SEC"1"
CDS_LOCATION"R135"
CDS_LMAN_SYM_OUTLINE"-50,50,100,-50"
CDS_LIB"passive"
TOLERANCE"-"
CLS_PN"G155-100R0-J0";
"1"
$PN"1"23;
"2"
$PN"2"72;
%"RESISTOR"
"1","(-11800,1050)","0","passive","I439";
;
$LOCATION"R137"
PACKAGE"0402"
VALUE"33OHM"
CDS_SEC"1"
$SEC"1"
CDS_LOCATION"R137"
SIGNAL_MODEL"DEFAULT_RESISTOR_33OHM_2_1"
CDS_LMAN_SYM_OUTLINE"-50,50,100,-50"
CDS_LIB"passive"
CLS_PN"G155-133R0-01"
TOLERANCE"1%";
"1"
$PN"1"22;
"2"
$PN"2"20;
%"RESISTOR"
"2","(-10250,800)","0","passive","I440";
;
$LOCATION"R402"
VALUE"2.2KOHM"
PACKAGE"0402"
CDS_SEC"1"
$SEC"1"
CDS_LOCATION"R402"
CLS_PN"G155-12201-01"
CDS_LIB"passive"
CDS_LMAN_SYM_OUTLINE"-50,50,50,-100"
TOLERANCE"1%";
"1"
$PN"1"67;
"2"
$PN"2"10;
%"GND_SG"
"1","(-10300,450)","0","cls","I441";
;
HDL_POWER"SG"
BODY_TYPE"PLUMBING"
CDS_LIB"cls"
CDS_LMAN_SYM_OUTLINE"0,0,100,-50";
"SGND"10;
%"DIODE_4_V1"
"1","(-11450,-200)","1","discrete","I442";
;
CDS_LOCATION"CR7"
LOCATION"CR7"
PART_NUMBER"SR3.3.TCT"
CLS_PN"G122-10123-01"
CDS_SEC"1"
$SEC"1"
CDS_LIB"discrete"
CDS_LMAN_SYM_OUTLINE"0,0,400,-600";
"VDD"
$PN"4"0;
"IO2"
$PN"3"23;
"IO1"
$PN"2"21;
"GND"
$PN"1"9;
%"DIODE_4_V1"
"1","(-12250,-200)","1","discrete","I443";
;
CDS_LOCATION"CR6"
LOCATION"CR6"
PART_NUMBER"SR3.3.TCT"
CLS_PN"G122-10123-01"
CDS_SEC"1"
$SEC"1"
CDS_LIB"discrete"
CDS_LMAN_SYM_OUTLINE"0,0,400,-600";
"VDD"
$PN"4"0;
"IO2"
$PN"3"22;
"IO1"
$PN"2"24;
"GND"
$PN"1"9;
%"GND_SG"
"1","(-12200,-500)","0","cls","I444";
;
HDL_POWER"SG"
CDS_LIB"cls"
CDS_LMAN_SYM_OUTLINE"0,0,100,-50"
BODY_TYPE"PLUMBING";
"SGND"9;
%"GND_SG"
"1","(-14050,-500)","0","cls","I445";
;
HDL_POWER"SG"
CDS_LMAN_SYM_OUTLINE"0,0,100,-50"
CDS_LIB"cls"
BODY_TYPE"PLUMBING";
"SGND"8;
%"RESISTOR"
"1","(-14300,350)","0","passive","I446";
;
$LOCATION"R133"
VALUE"33OHM"
CDS_SEC"1"
$SEC"1"
CDS_LOCATION"R133"
CDS_LIB"passive"
CDS_LMAN_SYM_OUTLINE"-50,50,100,-50"
SIGNAL_MODEL"DEFAULT_RESISTOR_33OHM_2_1"
CLS_PN"G155-133R0-01"
TOLERANCE"1%";
"1"
$PN"1"7;
"2"
$PN"2"44;
%"VCC"
"1","(-14550,550)","0","cls","I447";
;
VOLTAGE"3.3V"
HDL_POWER"XP3R3V_FPGA"
BODY_TYPE"PLUMBING"
CDS_LIB"cls"
CDS_LMAN_SYM_OUTLINE"-250,250,250,-250";
"$PIN0"7;
%"MT25QL128ABA1ESE_SOP8"
"1","(-6100,550)","0","memory","I456";
;
$LOCATION"U23"
VALUE"MT25QL128ABA1ESE-0SIT"
CLS_PN"G221-10224-01"
CDS_SEC"1"
$SEC"1"
CDS_LOCATION"U23"
CDS_LIB"memory"
CDS_LMAN_SYM_OUTLINE"0,0,800,-900";
"VCC"
$PN"8"5;
"HOLD/DQ3* \B"
$PN"7"34;
"C"
$PN"6"32;
"DQ0"
$PN"5"27;
"VSS"
$PN"4"3;
"W/DQ2* \B"
$PN"3"28;
"DQ1"
$PN"2"35;
"S* \B"
$PN"1"33;
%"VCC"
"1","(-3800,850)","0","cls","I457";
;
VOLTAGE"3.3V"
HDL_POWER"XP3R3V_FPGA"
BODY_TYPE"PLUMBING"
CDS_LIB"cls"
CDS_LMAN_SYM_OUTLINE"-250,250,250,-250";
"$PIN0"6;
%"RESISTOR"
"1","(-4500,700)","0","passive","I462";
;
$LOCATION"R199"
VALUE"4.7KOHM"
PACKAGE"0402"
CDS_SEC"1"
$SEC"1"
CDS_LOCATION"R199"
TOLERANCE"1%"
CLS_PN"G155-14701-01"
CDS_LMAN_SYM_OUTLINE"-50,50,100,-50"
CDS_LIB"passive";
"1"
$PN"1"27;
"2"
$PN"2"6;
%"RESISTOR"
"1","(-4500,500)","0","passive","I463";
;
CDS_LOCATION"R201"
LOCATION"R201"
VALUE"4.7KOHM"
PACKAGE"0402"
CDS_SEC"1"
$SEC"1"
TOLERANCE"1%"
CLS_PN"G155-14701-01"
CDS_LMAN_SYM_OUTLINE"-50,50,100,-50"
CDS_LIB"passive";
"1"
$PN"1"28;
"2"
$PN"2"6;
%"RESISTOR"
"1","(-4500,400)","0","passive","I464";
;
CDS_LOCATION"R202"
LOCATION"R202"
VALUE"4.7KOHM"
PACKAGE"0402"
CDS_SEC"1"
$SEC"1"
TOLERANCE"1%"
CDS_LIB"passive"
CDS_LMAN_SYM_OUTLINE"-50,50,100,-50"
CLS_PN"G155-14701-01";
"1"
$PN"1"34;
"2"
$PN"2"6;
%"RESISTOR"
"1","(-4500,600)","0","passive","I465";
;
CDS_LOCATION"R200"
LOCATION"R200"
VALUE"4.7KOHM"
PACKAGE"0402"
CDS_SEC"1"
$SEC"1"
TOLERANCE"1%"
CLS_PN"G155-14701-01"
CDS_LMAN_SYM_OUTLINE"-50,50,100,-50"
CDS_LIB"passive";
"1"
$PN"1"35;
"2"
$PN"2"6;
%"RESISTOR"
"1","(-4500,150)","0","passive","I466";
;
CDS_LOCATION"R204"
LOCATION"R204"
VALUE"33OHM"
PACKAGE"0402"
CDS_SEC"1"
$SEC"1"
TOLERANCE"1%"
CDS_LIB"passive"
CDS_LMAN_SYM_OUTLINE"-50,50,100,-50"
CLS_PN"G155-133R0-01";
"1"
$PN"1"35;
"2"
$PN"2"26;
%"RESISTOR"
"1","(-4500,250)","0","passive","I467";
;
$LOCATION"R203"
PACKAGE"0402"
VALUE"33OHM"
CDS_SEC"1"
$SEC"1"
CDS_LOCATION"R203"
TOLERANCE"1%"
CLS_PN"G155-133R0-01"
CDS_LMAN_SYM_OUTLINE"-50,50,100,-50"
CDS_LIB"passive";
"1"
$PN"1"27;
"2"
$PN"2"29;
%"RESISTOR"
"1","(-4500,50)","0","passive","I468";
;
CDS_LOCATION"R205"
LOCATION"R205"
VALUE"33OHM"
PACKAGE"0402"
CDS_SEC"1"
$SEC"1"
TOLERANCE"1%"
CDS_LIB"passive"
CDS_LMAN_SYM_OUTLINE"-50,50,100,-50"
CLS_PN"G155-133R0-01";
"1"
$PN"1"28;
"2"
$PN"2"25;
%"RESISTOR"
"1","(-4500,-50)","0","passive","I469";
;
CDS_LOCATION"R206"
LOCATION"R206"
VALUE"33OHM"
PACKAGE"0402"
CDS_SEC"1"
$SEC"1"
TOLERANCE"1%"
CLS_PN"G155-133R0-01"
CDS_LMAN_SYM_OUTLINE"-50,50,100,-50"
CDS_LIB"passive";
"1"
$PN"1"34;
"2"
$PN"2"31;
%"RESISTOR"
"2","(-6400,-200)","0","passive","I470";
;
$LOCATION"R192"
VALUE"4.7KOHM"
PACKAGE"0402"
CDS_SEC"1"
$SEC"1"
CDS_LOCATION"R192"
CDS_LMAN_SYM_OUTLINE"-50,50,50,-100"
CDS_LIB"passive"
CLS_PN"G155-14701-01"
TOLERANCE"1%";
"1"
$PN"1"32;
"2"
$PN"2"2;
%"RESISTOR"
"2","(-6500,500)","2","passive","I471";
;
$LOCATION"R191"
VALUE"4.7KOHM"
PACKAGE"0402"
CDS_SEC"1"
$SEC"1"
CDS_LOCATION"R191"
TOLERANCE"1%"
CLS_PN"G155-14701-01"
CDS_LMAN_SYM_OUTLINE"-50,50,50,-100"
CDS_LIB"passive";
"1"
$PN"1"5;
"2"
$PN"2"33;
%"CAPACITOR"
"2","(-7000,900)","0","passive","I472";
;
$LOCATION"C199"
VOLTAGE"10V"
PACKAGE"0402"
VALUE"0.1UF"
CDS_SEC"1"
$SEC"1"
CDS_LOCATION"C199"
CDS_LMAN_SYM_OUTLINE"-50,0,50,-50"
CDS_LIB"passive"
CLS_PN"G105-0B104-CK"
TOLERANCE"10%";
"2"
$PN"2"4;
"1"
$PN"1"5;
%"CAPACITOR"
"2","(-7600,900)","0","passive","I473";
;
$LOCATION"C198"
VALUE"4.7UF"
VOLTAGE"6.3V"
PACKAGE"0402"
CDS_SEC"1"
$SEC"1"
CDS_LOCATION"C198"
TOLERANCE"20%"
CLS_PN"G105-0F475-BM"
CDS_LMAN_SYM_OUTLINE"-50,0,50,-50"
CDS_LIB"passive";
"2"
$PN"2"4;
"1"
$PN"1"5;
%"VCC"
"1","(-7650,1250)","0","cls","I474";
;
VOLTAGE"3.3V"
HDL_POWER"XP3R3V_FPGA"
BODY_TYPE"PLUMBING"
CDS_LMAN_SYM_OUTLINE"-250,250,250,-250"
CDS_LIB"cls";
"$PIN0"5;
%"GND_SG"
"1","(-7650,500)","0","cls","I477";
;
HDL_POWER"SG"
CDS_LMAN_SYM_OUTLINE"0,0,100,-50"
CDS_LIB"cls"
BODY_TYPE"PLUMBING";
"SGND"4;
%"GND_SG"
"1","(-5150,-400)","0","cls","I478";
;
HDL_POWER"SG"
BODY_TYPE"PLUMBING"
CDS_LMAN_SYM_OUTLINE"0,0,100,-50"
CDS_LIB"cls";
"SGND"3;
%"GND_SG"
"1","(-6450,-500)","0","cls","I479";
;
HDL_POWER"SG"
BODY_TYPE"PLUMBING"
CDS_LMAN_SYM_OUTLINE"0,0,100,-50"
CDS_LIB"cls";
"SGND"2;
%"GND_SG"
"1","(-1050,2200)","0","cls","I75";
;
HDL_POWER"SG"
CDS_LMAN_SYM_OUTLINE"0,0,100,-50"
CDS_LIB"cls"
BODY_TYPE"PLUMBING";
"SGND"1;
END.
